FILE_TYPE = CONNECTIVITY;
{Allegro Design Entry HDL 17.4-2019 S026 (4007227) 1/17/2022}
"PAGE_NUMBER" = 470;
0"NC";
1"GND\g";
2"GND\g";
3"P3V3_AUX\g";
4"GND\g";
5"GND\g";
6"GND\g";
7"GND\g";
8"P3V3_AUX\g";
9"GND\g";
10"GND\g";
11"GND\g";
12"P1V8_RETIMER_CPU1_CS";
13"SW_P1V8_RETIMER_CPU1_SW";
14"PWRGD_P1V8_RETIMER_CPU1";
15"GND\g";
16"GND\g";
17"GND\g";
18"P1V8_CPU1_RT_1D\g";
19"P12V_AUX\g";
20"SW_P12V_AUX_P1V8_RETIMER_CPU1_FLT";
21"SW_P1V8_RETIMER_CPU1_BST_R";
22"SW_P1V8_RETIMER_CPU1_BST";
23"P1V8_RETIMER_CPU1_FB";
24"P1V8_RETIMER_CPU1_MODE";
25"P1V8_RETIMER_CPU1_REF";
26"FM_PWRGD_P1V8_RETIMER_CPU1";
27"P1V8_RETIMER_CPU1_VCC";
28"P1V8_RETIMER_CPU1_EN";
%"UNIVERSAL_GND"
"1","(-7975,2800)","0","pure_quanta_power","I10";
;
CDS_LIB"pure_quanta_power"
HDL_POWER"GND";
"A"1;
%"UNIVERSAL_GND"
"1","(-7500,2200)","0","pure_quanta_power","I11";
;
CDS_LIB"pure_quanta_power"
HDL_POWER"GND";
"A"2;
%"Q_CAP"
"1","(-7500,2425)","2","pure_quanta","I12";
;
LOCATION"PC6525"
SEC"1"
VALUE"1UF"
PACK_TYPE"C0402"
MATERIAL"X6S"
TOLERANCE"10%"
VOLTAGE"25V"
CDS_LIB"pure_quanta"
SIGNAL_MODEL"DEFAULT_CAPACITOR_100000PF_2_1"
SEC_TYPE"C0402"
PART_NUMBER"CH5104KEB02";
"B"
$PN"2"2;
"A"
$PN"1"27;
%"Q_RES"
"2","(-7500,2850)","0","pure_quanta","I13";
;
LOCATION"PR6521"
$SEC"1"
CDS_SEC"1"
MATERIAL"CHIP"
VALUE"0"
TOLERANCE"5%"
WATTAGE"1/16W"
PACK_TYPE"0402LF"
CDS_LIB"pure_quanta"
PART_NUMBER"CS00002JB13";
"A"
$PN"1"3;
"B"
$PN"2"27;
%"UNIVERSAL_POWER"
"1","(-7500,3050)","0","mstr_symbols","I14";
;
HDL_POWER"P3V3_AUX"
CDS_LIB"mstr_symbols";
"A"3;
%"UNIVERSAL_GND"
"1","(-7875,3625)","0","pure_quanta_power","I15";
;
CDS_LIB"pure_quanta_power"
HDL_POWER"GND";
"A"15;
%"Q_CAP"
"1","(-8075,4000)","0","pure_quanta","I16";
;
LOCATION"PC6520"
$SEC"1"
CDS_SEC"1"
PACK_TYPE"C0805"
VALUE"22UF"
MATERIAL"X6S"
VOLTAGE"16V"
TOLERANCE"20%"
CDS_LIB"pure_quanta"
PART_NUMBER"CH6223MEA01";
"B"
$PN"2"15;
"A"
$PN"1"20;
%"Q_CAP"
"1","(-7850,4000)","0","pure_quanta","I17";
;
LOCATION"PC6521"
$SEC"1"
CDS_SEC"1"
TOLERANCE"20%"
VOLTAGE"16V"
VALUE"22UF"
MATERIAL"X6S"
PACK_TYPE"C0805"
CDS_LIB"pure_quanta"
PART_NUMBER"CH6223MEA01";
"B"
$PN"2"15;
"A"
$PN"1"20;
%"Q_CAP"
"1","(-7675,4000)","0","pure_quanta","I18";
;
LOCATION"PC6522"
$SEC"1"
CDS_SEC"1"
TOLERANCE"20%"
VALUE"22UF"
VOLTAGE"16V"
PACK_TYPE"C0805"
MATERIAL"X6S"
CDS_LIB"pure_quanta"
PART_NUMBER"CH6223MEA01";
"B"
$PN"2"15;
"A"
$PN"1"20;
%"UNIVERSAL_GND"
"1","(-6625,2175)","0","pure_quanta_power","I19";
;
CDS_LIB"pure_quanta_power"
HDL_POWER"GND";
"A"4;
%"UNIVERSAL_GND"
"1","(-9150,3700)","0","pure_quanta_power","I2";
;
CDS_LIB"pure_quanta_power"
HDL_POWER"GND";
"A"5;
%"Q_RES"
"2","(-6625,2425)","0","pure_quanta","I20";
;
LOCATION"PR6522"
SEC"1"
VALUE"7.15K"
TOLERANCE"1%"
MATERIAL"CHIP"
PACK_TYPE"0402LF"
WATTAGE"1/16W"
CDS_LIB"pure_quanta"
SEC_TYPE"0402LF"
PART_NUMBER"CS27152FB03";
"A"
$PN"1"12;
"B"
$PN"2"4;
%"Q_RES"
"1","(-7000,3250)","0","pure_quanta","I21";
;
LOCATION"PR6520"
$SEC"1"
CDS_SEC"1"
VALUE"0"
MATERIAL"CHIP"
TOLERANCE"5%"
PACK_TYPE"0402LF"
WATTAGE"1/16W"
CDS_LIB"pure_quanta"
PART_NUMBER"CS00002JB13";
"B"
$PN"2"24;
"A"
$PN"1"1;
%"Q_CAP"
"1","(-7450,4000)","0","pure_quanta","I22";
;
LOCATION"PC6523"
$SEC"1"
CDS_SEC"1"
TOLERANCE"20%"
VOLTAGE"16V"
VALUE"22UF"
MATERIAL"X6S"
PACK_TYPE"C0805"
CDS_LIB"pure_quanta"
PART_NUMBER"CH6223MEA01";
"B"
$PN"2"15;
"A"
$PN"1"20;
%"Q_CAP"
"1","(-7250,4000)","0","pure_quanta","I23";
;
LOCATION"PC6524"
$SEC"1"
CDS_SEC"1"
PACK_TYPE"C0402"
VALUE"1UF"
MATERIAL"X6S"
VOLTAGE"25V"
TOLERANCE"10%"
CDS_LIB"pure_quanta"
PART_NUMBER"CH5104KEB02";
"B"
$PN"2"15;
"A"
$PN"1"20;
%"UNIVERSAL_GND"
"1","(-5050,2325)","0","pure_quanta_power","I24";
;
CDS_LIB"pure_quanta_power"
HDL_POWER"GND";
"A"16;
%"Q_CAP"
"1","(-4925,2575)","0","pure_quanta","I25";
;
LOCATION"PC6537"
$SEC"1"
CDS_SEC"1"
VALUE"0.1UF"
PACK_TYPE"0402"
VOLTAGE"25V"
MATERIAL"X7R"
TOLERANCE"10%"
CDS_LIB"pure_quanta"
PART_NUMBER"CH4104K1B00";
"B"
$PN"2"6;
"A"
$PN"1"25;
%"UNIVERSAL_GND"
"1","(-4925,2325)","0","pure_quanta_power","I26";
;
CDS_LIB"pure_quanta_power"
HDL_POWER"GND";
"A"6;
%"UNIVERSAL_GND"
"1","(-4550,2325)","0","pure_quanta_power","I27";
;
CDS_LIB"pure_quanta_power"
HDL_POWER"GND";
"A"7;
%"Q_RES"
"1","(-4525,3750)","0","pure_quanta","I28";
;
LOCATION"PR6801"
$SEC"1"
CDS_SEC"1"
MATERIAL"CHIP"
VALUE"2.2"
PACK_TYPE"0402LF"
TOLERANCE"1%"
WATTAGE"1/16W"
CDS_LIB"pure_quanta"
PART_NUMBER"CS-2202FB01";
"B"
$PN"2"21;
"A"
$PN"1"22;
%"Q_RES"
"2","(-4625,4250)","0","pure_quanta","I29";
;
LOCATION"R644"
SEC"1"
MATERIAL"CHIP"
WATTAGE"1/16W"
TOLERANCE"5%"
VALUE"10K"
PACK_TYPE"0402LF"
CDS_LIB"pure_quanta"
SEC_TYPE"0402LF"
PART_NUMBER"CS31002JB08";
"A"
$PN"1"8;
"B"
$PN"2"14;
%"Q_CAP"
"1","(-9150,4025)","0","pure_quanta","I3";
;
LOCATION"PC6519"
$SEC"1"
CDS_SEC"1"
MATERIAL"X6S"
VALUE"0.1UF"
PACK_TYPE"C0402"
VOLTAGE"25V"
TOLERANCE"10%"
CDS_LIB"pure_quanta"
PART_NUMBER"CH4104KEB00";
"B"
$PN"2"5;
"A"
$PN"1"19;
%"UNIVERSAL_POWER"
"1","(-4625,4525)","0","mstr_symbols","I30";
;
HDL_POWER"P3V3_AUX"
CDS_LIB"mstr_symbols";
"A"8;
%"UNIVERSAL_GND"
"1","(-4075,2200)","0","pure_quanta_power","I31";
;
CDS_LIB"pure_quanta_power"
HDL_POWER"GND";
"A"9;
%"Q_RES"
"2","(-4075,2475)","0","pure_quanta","I32";
;
LOCATION"PR6526"
$SEC"1"
CDS_SEC"1"
PACK_TYPE"0402LF"
MATERIAL"CHIP"
WATTAGE"1/16W"
TOLERANCE"1%"
VALUE"10K"
CDS_LIB"pure_quanta"
PART_NUMBER"CS31002FB08";
"A"
$PN"1"23;
"B"
$PN"2"9;
%"Q_CAP"
"2","(-3500,2675)","0","pure_quanta","I33";
;
LOCATION"PC6534"
$SEC"1"
CDS_SEC"1"
MATERIAL"NPO"
TOLERANCE"5%"
VALUE"150PF"
PACK_TYPE"0402"
VOLTAGE"50V"
CDS_LIB"pure_quanta"
PART_NUMBER"TMP_QCH11506JB08";
"A"
$PN"1"23;
"B"
$PN"2"18;
%"Q_RES"
"1","(-3500,3000)","0","pure_quanta","I34";
;
LOCATION"PR6524"
$SEC"1"
CDS_SEC"1"
MATERIAL"CHIP"
VALUE"20K"
PACK_TYPE"0402LF"
CDS_LIB"pure_quanta"
WATTAGE"1/16W"
TOLERANCE"1%"
PART_NUMBER"CS32002FB06";
"B"
$PN"2"18;
"A"
$PN"1"23;
%"Q_CAP"
"1","(-3925,3625)","0","pure_quanta","I35";
;
LOCATION"PC6526"
SEC"1"
TOLERANCE"10%"
MATERIAL"X7R"
VOLTAGE"16V"
PACK_TYPE"0402"
VALUE"0.22UF"
SEC_TYPE"0402"
CDS_LIB"pure_quanta"
PART_NUMBER"CH4223K1B00";
"B"
$PN"2"13;
"A"
$PN"1"21;
%"Q_RES"
"1","(-3575,3950)","0","pure_quanta","I36";
;
LOCATION"R645"
$SEC"1"
CDS_SEC"1"
VALUE"33"
PACK_TYPE"0402LF"
TOLERANCE"5%"
MATERIAL"CHIP"
WATTAGE"1/16W"
BOM_COST"MEM"
CDS_LIB"pure_quanta"
PART_NUMBER"CS03302JB10";
"B"
$PN"2"26;
"A"
$PN"1"14;
%"Q_INDUCTOR"
"1","(-3500,3475)","0","pure_quanta","I37";
;
LOCATION"PL6502"
$SEC"1"
CDS_SEC"1"
VALUE"1UH"
MATERIAL"IND"
PACK_TYPE"SMLF"
NEEDS_NO_SIZE"TRUE"
CDS_LIB"pure_quanta"
PART_NUMBER"CV-10U0MZ01";
"1"
$PN"1"13;
"2"
$PN"2"18;
%"Q_CAP"
"1","(-2850,3200)","0","pure_quanta","I38";
;
LOCATION"PC6527"
$SEC"1"
CDS_SEC"1"
VOLTAGE"4V"
TOLERANCE"20%"
MATERIAL"X6S"
VALUE"22UF"
PACK_TYPE"C0805"
CDS_LIB"pure_quanta"
PART_NUMBER"CH622KMEA03";
"B"
$PN"2"17;
"A"
$PN"1"18;
%"Q_CAP"
"1","(-2775,3800)","0","pure_quanta","I39";
;
LOCATION"C109"
$SEC"1"
CDS_SEC"1"
VOLTAGE"50V"
MATERIAL"X7R"
VALUE"1000PF"
TOLERANCE"5%"
PACK_TYPE"0402"
CDS_LIB"pure_quanta"
PART_NUMBER"TMP_QCH21006JB10";
"B"
$PN"2"11;
"A"
$PN"1"26;
%"UNIVERSAL_GND"
"1","(-8500,3050)","0","pure_quanta_power","I4";
;
CDS_LIB"pure_quanta_power"
HDL_POWER"GND";
"A"10;
%"UNIVERSAL_GND"
"1","(-2775,3600)","0","pure_quanta_power","I40";
;
CDS_LIB"pure_quanta_power"
HDL_POWER"GND";
"A"11;
%"Q_CAP"
"1","(-2425,3200)","0","pure_quanta","I41";
;
LOCATION"PC6528"
$SEC"1"
CDS_SEC"1"
MATERIAL"X6S"
PACK_TYPE"C0805"
VOLTAGE"4V"
TOLERANCE"20%"
VALUE"22UF"
CDS_LIB"pure_quanta"
PART_NUMBER"CH622KMEA03";
"B"
$PN"2"17;
"A"
$PN"1"18;
%"Q_CAP"
"1","(-2150,3200)","0","pure_quanta","I42";
;
LOCATION"PC6529"
$SEC"1"
CDS_SEC"1"
MATERIAL"X6S"
TOLERANCE"20%"
PACK_TYPE"C0805"
VOLTAGE"4V"
VALUE"22UF"
CDS_LIB"pure_quanta"
PART_NUMBER"CH622KMEA03";
"B"
$PN"2"17;
"A"
$PN"1"18;
%"Q_CAP"
"1","(-1900,3200)","0","pure_quanta","I44";
;
LOCATION"PC6530"
$SEC"1"
CDS_SEC"1"
TOLERANCE"20%"
VOLTAGE"4V"
PACK_TYPE"C0805"
VALUE"22UF"
MATERIAL"X6S"
CDS_LIB"pure_quanta"
PART_NUMBER"CH622KMEA03";
"B"
$PN"2"17;
"A"
$PN"1"18;
%"Q_CAP"
"1","(-1625,3200)","0","pure_quanta","I45";
;
LOCATION"PC6531"
$SEC"1"
CDS_SEC"1"
PACK_TYPE"C0805"
VOLTAGE"4V"
VALUE"22UF"
MATERIAL"X6S"
TOLERANCE"20%"
CDS_LIB"pure_quanta"
PART_NUMBER"CH622KMEA03";
"B"
$PN"2"17;
"A"
$PN"1"18;
%"Q_CAPP"
"1","(-1350,3200)","0","pure_quanta","I46";
;
LOCATION"PC6532"
$SEC"1"
CDS_SEC"1"
PACK_TYPE"SMLF"
MATERIAL"ALUM"
VALUE"390UF"
TOLERANCE"20%"
VOLTAGE"2.5V"
CDS_LIB"pure_quanta"
PART_NUMBER"CC7390JMZ13";
"A"
$PN"1"18;
"B"
$PN"2"17;
%"Q_CAPP"
"1","(-1050,3200)","0","pure_quanta","I47";
;
LOCATION"PC6804"
$SEC"1"
CDS_SEC"1"
PACK_TYPE"SMLF"
VOLTAGE"2.5V"
VALUE"390UF"
MATERIAL"ALUM"
TOLERANCE"20%"
CDS_LIB"pure_quanta"
PART_NUMBER"CC7390JMZ13";
"A"
$PN"1"18;
"B"
$PN"2"17;
%"UNIVERSAL_GND"
"1","(-1025,2825)","0","pure_quanta_power","I48";
;
CDS_LIB"pure_quanta_power"
HDL_POWER"GND";
"A"17;
%"Q_CAP"
"1","(-750,3200)","0","pure_quanta","I49";
;
LOCATION"PC6533"
SEC"1"
MATERIAL"X7R"
TOLERANCE"10%"
PACK_TYPE"0402"
VALUE"0.1UF"
VOLTAGE"25V"
CDS_LIB"pure_quanta"
SEC_TYPE"0402"
PART_NUMBER"CH4104K1B00";
"B"
$PN"2"17;
"A"
$PN"1"18;
%"Q_CAP"
"1","(-8500,3250)","2","pure_quanta","I5";
;
LOCATION"C105"
$SEC"1"
CDS_SEC"1"
PACK_TYPE"0402"
MATERIAL"EMPTY"
TOLERANCE"10%"
VOLTAGE"25V"
VALUE"0.1UF"
CDS_LIB"pure_quanta"
PART_NUMBER"CH4104K1B00";
"B"
$PN"2"10;
"A"
$PN"1"28;
%"P1V0"
"1","(-425,3825)","0","pure_quanta_power","I50";
;
HDL_POWER"P1V8_CPU1_RT_1D"
CDS_LIB"pure_quanta_power";
"A"18;
%"MPQ8633BGLEC838Z"
"1","(-5675,3275)","0","pure_quanta","I51";
;
LOCATION"PU6501"
$SEC"1"
CDS_SEC"1"
VALUE"MPQ8633BGLE-C838-Z"
PART_TYPE"SMLF"
MATERIAL"IC"
CDS_LMAN_SYM_OUTLINE"-250,725,250,-725"
NEEDS_NO_SIZE"TRUE"
CDS_LIB"pure_quanta"
PART_NUMBER"AL008633005";
"VIN2"
$PN"21"20;
"CS"
$PN"3"12;
"MODE"
$PN"4"24;
"TRK_REF"
$PN"5"25;
"SW"
$PN"20"13;
"RGND"
$PN"6"7;
"VCC"
$PN"19"27;
"AGND"
$PN"2"16;
"FB"
$PN"7"23;
"BST"
$PN"1"22;
"EN"
$PN"8"28;
"PGND"
$PN"11_18"16;
"PGOOD"
$PN"9"14;
"VIN1"
$PN"10"20;
%"Q_CAP"
"1","(-6525,4000)","0","pure_quanta","I55";
;
LOCATION"PC6905"
$SEC"1"
CDS_SEC"1"
TOLERANCE"20%"
VALUE"22UF"
VOLTAGE"16V"
MATERIAL"X6S"
PACK_TYPE"C0805"
CDS_LIB"pure_quanta"
PART_NUMBER"CH6223MEA01";
"B"
$PN"2"15;
"A"
$PN"1"20;
%"Q_CAP"
"1","(-6700,4000)","0","pure_quanta","I56";
;
LOCATION"PC6904"
$SEC"1"
CDS_SEC"1"
VOLTAGE"16V"
VALUE"22UF"
TOLERANCE"20%"
MATERIAL"X6S"
PACK_TYPE"C0805"
CDS_LIB"pure_quanta"
PART_NUMBER"CH6223MEA01";
"B"
$PN"2"15;
"A"
$PN"1"20;
%"Q_CAP"
"1","(-6900,4000)","0","pure_quanta","I57";
;
LOCATION"PC6903"
$SEC"1"
CDS_SEC"1"
PACK_TYPE"C0805"
MATERIAL"X6S"
TOLERANCE"20%"
VOLTAGE"16V"
VALUE"22UF"
CDS_LIB"pure_quanta"
PART_NUMBER"CH6223MEA01";
"B"
$PN"2"15;
"A"
$PN"1"20;
%"Q_CAPP"
"1","(-8525,4000)","2","pure_quanta","I6";
;
LOCATION"PC6801"
$SEC"1"
CDS_SEC"1"
PACK_TYPE"SMLF"
VOLTAGE"16V"
TOLERANCE"20%"
MATERIAL"OSCON"
VALUE"270UF"
CDS_LIB"pure_quanta"
PART_NUMBER"CC72703MZ11";
"A"
$PN"1"20;
"B"
$PN"2"15;
%"Q_CAP"
"1","(-8400,4000)","0","pure_quanta","I7";
;
LOCATION"PC6803"
$SEC"1"
CDS_SEC"1"
VOLTAGE"16V"
VALUE"22UF"
PACK_TYPE"C0805"
MATERIAL"X6S"
TOLERANCE"20%"
CDS_LIB"pure_quanta"
PART_NUMBER"CH6223MEA01";
"B"
$PN"2"15;
"A"
$PN"1"20;
%"P1V0_AUX"
"1","(-9150,4425)","0","mstr_symbols","I8";
;
HDL_POWER"P12V_AUX"
CDS_LIB"mstr_symbols"
VOLTAGE"1.0V"
ROOM"VR_DDR1_POWER_STAGE"
BODY_TYPE"PLUMBING";
"A"19;
%"Q_INDUCTOR"
"1","(-8800,4250)","0","pure_quanta","I9";
;
LOCATION"PL6503"
$SEC"1"
CDS_SEC"1"
VALUE"100NH/16A"
PACK_TYPE"SMLF"
MATERIAL"IND"
CDS_LIB"pure_quanta"
NEEDS_NO_SIZE"TRUE"
PART_NUMBER"CV+10G0MZ04";
"1"
$PN"1"19;
"2"
$PN"2"20;
END.
